(kicad_pcb
	(version 20260206)
	(generator "pcbnew")
	(generator_version "10.0")
	(general
		(thickness 1.6)
		(legacy_teardrops no)
	)
	(paper "A4")
	(title_block
		(title "03242023_DA0F0TMBIJ0_F0T_Motherboard_J_brd_V01_OCP.brd")
		(comment 1 "Grand Teton / footprint 1065 of 6105 (J26), pads 225-291 of 291")
	)
	(layers
		(0 "F.Cu" signal "TOP")
		(4 "In1.Cu" signal "GND")
		(6 "In2.Cu" signal "IN1")
		(8 "In3.Cu" signal "GND1")
		(10 "In4.Cu" signal "IN2")
		(12 "In5.Cu" signal "GND2")
		(14 "In6.Cu" signal "IN3")
		(16 "In7.Cu" signal "GND3")
		(18 "In8.Cu" signal "VCC")
		(20 "In9.Cu" signal "VCC1")
		(22 "In10.Cu" signal "GND4")
		(24 "In11.Cu" signal "IN4")
		(26 "In12.Cu" signal "GND5")
		(28 "In13.Cu" signal "IN5")
		(30 "In14.Cu" signal "GND6")
		(32 "In15.Cu" signal "IN6")
		(34 "In16.Cu" signal "GND7")
		(2 "B.Cu" signal "BOTTOM")
		(9 "F.Adhes" user "F.Adhesive")
		(11 "B.Adhes" user "B.Adhesive")
		(13 "F.Paste" user "Package Geometry/Pastemask Top")
		(15 "B.Paste" user "Package Geometry/Pastemask Bottom")
		(5 "F.SilkS" user "Ref Des/Silkscreen Top")
		(7 "B.SilkS" user "Ref Des/Silkscreen Bottom")
		(1 "F.Mask" user "Board Geometry/Soldermask Top")
		(3 "B.Mask" user "Board Geometry/Soldermask Bottom")
		(17 "Dwgs.User" user "User.Drawings")
		(19 "Cmts.User" user "User.Comments")
		(21 "Eco1.User" user "User.Eco1")
		(23 "Eco2.User" user "User.Eco2")
		(25 "Edge.Cuts" user "Board Geometry/Outline")
		(27 "Margin" user)
		(31 "F.CrtYd" user "Package Geometry/Place Bound Top")
		(29 "B.CrtYd" user "Package Geometry/Place Bound Bottom")
		(35 "F.Fab" user "Ref Des/Assembly Top")
		(33 "B.Fab" user "Ref Des/Assembly Bottom")
	)
	(footprint ""
		(layer "F.Cu")
		(at 160.86328 -258.091686)
		(property "Reference" "J26"
			(at -3.683 -81.702148 0)
			(unlocked yes)
			(layer "F.SilkS")
			(effects
				(font
					(size 0.7874 0.5842)
					(thickness 0.1524)
				)
				(justify left)
			)
		)
		(property "Value" ""
			(at 0 0 0)
			(layer "F.Fab")
			(effects
				(font
					(size 1.27 1.27)
				)
			)
		)
		(duplicate_pad_numbers_are_jumpers no)
		(pad "225" smd rect
			(at 2.050034 9.774936 270)
			(size 0.519938 1.4986)
			(layers "F.Cu" "F.Mask" "F.Paste")
			(net "M_E_CPU1_SB_CA<5>")
		)
		(pad "226" smd rect
			(at 2.050034 10.625074 270)
			(size 0.519938 1.4986)
			(layers "F.Cu" "F.Mask" "F.Paste")
			(net "GND")
		)
		(pad "227" smd rect
			(at 2.050034 11.474958 270)
			(size 0.519938 1.4986)
			(layers "F.Cu" "F.Mask" "F.Paste")
			(net "M_E_CPU1_SB_PAR")
		)
		(pad "228" smd rect
			(at 2.050034 12.325096 270)
			(size 0.519938 1.4986)
			(layers "F.Cu" "F.Mask" "F.Paste")
			(net "GND")
		)
		(pad "229" smd rect
			(at 2.050034 13.17498 270)
			(size 0.519938 1.4986)
			(layers "F.Cu" "F.Mask" "F.Paste")
			(net "M_E_CPU1_SB_CS_N<3>")
		)
		(pad "230" smd rect
			(at 2.050034 14.025118 270)
			(size 0.519938 1.4986)
			(layers "F.Cu" "F.Mask" "F.Paste")
			(net "GND")
		)
		(pad "231" smd rect
			(at 2.050034 14.875002 270)
			(size 0.519938 1.4986)
			(layers "F.Cu" "F.Mask" "F.Paste")
			(net "TP_CHE_CPU1_DIMM2_FRU_5")
		)
		(pad "232" smd rect
			(at 2.050034 15.724886 270)
			(size 0.519938 1.4986)
			(layers "F.Cu" "F.Mask" "F.Paste")
			(net "TP_CHE_CPU1_DIMM2_FRU_6")
		)
		(pad "233" smd rect
			(at 2.050034 16.575024 270)
			(size 0.519938 1.4986)
			(layers "F.Cu" "F.Mask" "F.Paste")
			(net "GND")
		)
		(pad "234" smd rect
			(at 2.050034 17.424908 270)
			(size 0.519938 1.4986)
			(layers "F.Cu" "F.Mask" "F.Paste")
			(net "M_E_CPU1_SB_CB<6>")
		)
		(pad "235" smd rect
			(at 2.050034 18.275046 270)
			(size 0.519938 1.4986)
			(layers "F.Cu" "F.Mask" "F.Paste")
			(net "GND")
		)
		(pad "236" smd rect
			(at 2.050034 19.12493 270)
			(size 0.519938 1.4986)
			(layers "F.Cu" "F.Mask" "F.Paste")
			(net "M_E_CPU1_SB_CB<7>")
		)
		(pad "237" smd rect
			(at 2.050034 19.975068 270)
			(size 0.519938 1.4986)
			(layers "F.Cu" "F.Mask" "F.Paste")
			(net "GND")
		)
		(pad "238" smd rect
			(at 2.050034 20.824952 270)
			(size 0.519938 1.4986)
			(layers "F.Cu" "F.Mask" "F.Paste")
			(net "M_E_CPU1_SB_DQS_DN<4>")
		)
		(pad "239" smd rect
			(at 2.050034 21.67509 270)
			(size 0.519938 1.4986)
			(layers "F.Cu" "F.Mask" "F.Paste")
			(net "M_E_CPU1_SB_DQS_DP<4>")
		)
		(pad "240" smd rect
			(at 2.050034 22.524974 270)
			(size 0.519938 1.4986)
			(layers "F.Cu" "F.Mask" "F.Paste")
			(net "GND")
		)
		(pad "241" smd rect
			(at 2.050034 23.375112 270)
			(size 0.519938 1.4986)
			(layers "F.Cu" "F.Mask" "F.Paste")
			(net "M_E_CPU1_SB_CB<2>")
		)
		(pad "242" smd rect
			(at 2.050034 24.224996 270)
			(size 0.519938 1.4986)
			(layers "F.Cu" "F.Mask" "F.Paste")
			(net "GND")
		)
		(pad "243" smd rect
			(at 2.050034 25.07488 270)
			(size 0.519938 1.4986)
			(layers "F.Cu" "F.Mask" "F.Paste")
			(net "M_E_CPU1_SB_CB<3>")
		)
		(pad "244" smd rect
			(at 2.050034 25.925018 270)
			(size 0.519938 1.4986)
			(layers "F.Cu" "F.Mask" "F.Paste")
			(net "GND")
		)
		(pad "245" smd rect
			(at 2.050034 26.774902 270)
			(size 0.519938 1.4986)
			(layers "F.Cu" "F.Mask" "F.Paste")
			(net "M_E_CPU1_SB_DQ<2>")
		)
		(pad "246" smd rect
			(at 2.050034 27.62504 270)
			(size 0.519938 1.4986)
			(layers "F.Cu" "F.Mask" "F.Paste")
			(net "GND")
		)
		(pad "247" smd rect
			(at 2.050034 28.474924 270)
			(size 0.519938 1.4986)
			(layers "F.Cu" "F.Mask" "F.Paste")
			(net "M_E_CPU1_SB_DQ<3>")
		)
		(pad "248" smd rect
			(at 2.050034 29.325062 270)
			(size 0.519938 1.4986)
			(layers "F.Cu" "F.Mask" "F.Paste")
			(net "GND")
		)
		(pad "249" smd rect
			(at 2.050034 30.174946 270)
			(size 0.519938 1.4986)
			(layers "F.Cu" "F.Mask" "F.Paste")
			(net "M_E_CPU1_SB_DQS_DN<5>")
		)
		(pad "250" smd rect
			(at 2.050034 31.025084 270)
			(size 0.519938 1.4986)
			(layers "F.Cu" "F.Mask" "F.Paste")
			(net "M_E_CPU1_SB_DQS_DP<5>")
		)
		(pad "251" smd rect
			(at 2.050034 31.874968 270)
			(size 0.519938 1.4986)
			(layers "F.Cu" "F.Mask" "F.Paste")
			(net "GND")
		)
		(pad "252" smd rect
			(at 2.050034 32.725106 270)
			(size 0.519938 1.4986)
			(layers "F.Cu" "F.Mask" "F.Paste")
			(net "M_E_CPU1_SB_DQ<6>")
		)
		(pad "253" smd rect
			(at 2.050034 33.57499 270)
			(size 0.519938 1.4986)
			(layers "F.Cu" "F.Mask" "F.Paste")
			(net "GND")
		)
		(pad "254" smd rect
			(at 2.050034 34.425128 270)
			(size 0.519938 1.4986)
			(layers "F.Cu" "F.Mask" "F.Paste")
			(net "M_E_CPU1_SB_DQ<7>")
		)
		(pad "255" smd rect
			(at 2.050034 35.275012 270)
			(size 0.519938 1.4986)
			(layers "F.Cu" "F.Mask" "F.Paste")
			(net "GND")
		)
		(pad "256" smd rect
			(at 2.050034 36.124896 270)
			(size 0.519938 1.4986)
			(layers "F.Cu" "F.Mask" "F.Paste")
			(net "M_E_CPU1_SB_DQ<10>")
		)
		(pad "257" smd rect
			(at 2.050034 36.975034 270)
			(size 0.519938 1.4986)
			(layers "F.Cu" "F.Mask" "F.Paste")
			(net "GND")
		)
		(pad "258" smd rect
			(at 2.050034 37.824918 270)
			(size 0.519938 1.4986)
			(layers "F.Cu" "F.Mask" "F.Paste")
			(net "M_E_CPU1_SB_DQ<11>")
		)
		(pad "259" smd rect
			(at 2.050034 38.675056 270)
			(size 0.519938 1.4986)
			(layers "F.Cu" "F.Mask" "F.Paste")
			(net "GND")
		)
		(pad "260" smd rect
			(at 2.050034 39.52494 270)
			(size 0.519938 1.4986)
			(layers "F.Cu" "F.Mask" "F.Paste")
			(net "M_E_CPU1_SB_DQS_DN<6>")
		)
		(pad "261" smd rect
			(at 2.050034 40.375078 270)
			(size 0.519938 1.4986)
			(layers "F.Cu" "F.Mask" "F.Paste")
			(net "M_E_CPU1_SB_DQS_DP<6>")
		)
		(pad "262" smd rect
			(at 2.050034 41.224962 270)
			(size 0.519938 1.4986)
			(layers "F.Cu" "F.Mask" "F.Paste")
			(net "GND")
		)
		(pad "263" smd rect
			(at 2.050034 42.0751 270)
			(size 0.519938 1.4986)
			(layers "F.Cu" "F.Mask" "F.Paste")
			(net "M_E_CPU1_SB_DQ<14>")
		)
		(pad "264" smd rect
			(at 2.050034 42.924984 270)
			(size 0.519938 1.4986)
			(layers "F.Cu" "F.Mask" "F.Paste")
			(net "GND")
		)
		(pad "265" smd rect
			(at 2.050034 43.775122 270)
			(size 0.519938 1.4986)
			(layers "F.Cu" "F.Mask" "F.Paste")
			(net "M_E_CPU1_SB_DQ<15>")
		)
		(pad "266" smd rect
			(at 2.050034 44.625006 270)
			(size 0.519938 1.4986)
			(layers "F.Cu" "F.Mask" "F.Paste")
			(net "GND")
		)
		(pad "267" smd rect
			(at 2.050034 45.47489 270)
			(size 0.519938 1.4986)
			(layers "F.Cu" "F.Mask" "F.Paste")
			(net "M_E_CPU1_SB_DQ<18>")
		)
		(pad "268" smd rect
			(at 2.050034 46.325028 270)
			(size 0.519938 1.4986)
			(layers "F.Cu" "F.Mask" "F.Paste")
			(net "GND")
		)
		(pad "269" smd rect
			(at 2.050034 47.174912 270)
			(size 0.519938 1.4986)
			(layers "F.Cu" "F.Mask" "F.Paste")
			(net "M_E_CPU1_SB_DQ<19>")
		)
		(pad "270" smd rect
			(at 2.050034 48.02505 270)
			(size 0.519938 1.4986)
			(layers "F.Cu" "F.Mask" "F.Paste")
			(net "GND")
		)
		(pad "271" smd rect
			(at 2.050034 48.874934 270)
			(size 0.519938 1.4986)
			(layers "F.Cu" "F.Mask" "F.Paste")
			(net "M_E_CPU1_SB_DQS_DN<7>")
		)
		(pad "272" smd rect
			(at 2.050034 49.725072 270)
			(size 0.519938 1.4986)
			(layers "F.Cu" "F.Mask" "F.Paste")
			(net "M_E_CPU1_SB_DQS_DP<7>")
		)
		(pad "273" smd rect
			(at 2.050034 50.574956 270)
			(size 0.519938 1.4986)
			(layers "F.Cu" "F.Mask" "F.Paste")
			(net "GND")
		)
		(pad "274" smd rect
			(at 2.050034 51.425094 270)
			(size 0.519938 1.4986)
			(layers "F.Cu" "F.Mask" "F.Paste")
			(net "M_E_CPU1_SB_DQ<22>")
		)
		(pad "275" smd rect
			(at 2.050034 52.274978 270)
			(size 0.519938 1.4986)
			(layers "F.Cu" "F.Mask" "F.Paste")
			(net "GND")
		)
		(pad "276" smd rect
			(at 2.050034 53.125116 270)
			(size 0.519938 1.4986)
			(layers "F.Cu" "F.Mask" "F.Paste")
			(net "M_E_CPU1_SB_DQ<23>")
		)
		(pad "277" smd rect
			(at 2.050034 53.975 270)
			(size 0.519938 1.4986)
			(layers "F.Cu" "F.Mask" "F.Paste")
			(net "GND")
		)
		(pad "278" smd rect
			(at 2.050034 54.824884 270)
			(size 0.519938 1.4986)
			(layers "F.Cu" "F.Mask" "F.Paste")
			(net "M_E_CPU1_SB_DQ<26>")
		)
		(pad "279" smd rect
			(at 2.050034 55.675022 270)
			(size 0.519938 1.4986)
			(layers "F.Cu" "F.Mask" "F.Paste")
			(net "GND")
		)
		(pad "280" smd rect
			(at 2.050034 56.524906 270)
			(size 0.519938 1.4986)
			(layers "F.Cu" "F.Mask" "F.Paste")
			(net "M_E_CPU1_SB_DQ<27>")
		)
		(pad "281" smd rect
			(at 2.050034 57.375044 270)
			(size 0.519938 1.4986)
			(layers "F.Cu" "F.Mask" "F.Paste")
			(net "GND")
		)
		(pad "282" smd rect
			(at 2.050034 58.224928 270)
			(size 0.519938 1.4986)
			(layers "F.Cu" "F.Mask" "F.Paste")
			(net "M_E_CPU1_SB_DQS_DN<8>")
		)
		(pad "283" smd rect
			(at 2.050034 59.075066 270)
			(size 0.519938 1.4986)
			(layers "F.Cu" "F.Mask" "F.Paste")
			(net "M_E_CPU1_SB_DQS_DP<8>")
		)
		(pad "284" smd rect
			(at 2.050034 59.92495 270)
			(size 0.519938 1.4986)
			(layers "F.Cu" "F.Mask" "F.Paste")
			(net "GND")
		)
		(pad "285" smd rect
			(at 2.050034 60.775088 270)
			(size 0.519938 1.4986)
			(layers "F.Cu" "F.Mask" "F.Paste")
			(net "M_E_CPU1_SB_DQ<30>")
		)
		(pad "286" smd rect
			(at 2.050034 61.624972 270)
			(size 0.519938 1.4986)
			(layers "F.Cu" "F.Mask" "F.Paste")
			(net "GND")
		)
		(pad "287" smd rect
			(at 2.050034 62.47511 270)
			(size 0.519938 1.4986)
			(layers "F.Cu" "F.Mask" "F.Paste")
			(net "M_E_CPU1_SB_DQ<31>")
		)
		(pad "288" smd rect
			(at 2.050034 63.324994 270)
			(size 0.519938 1.4986)
			(layers "F.Cu" "F.Mask" "F.Paste")
			(net "GND")
		)
		(pad "G1" thru_hole oval
			(at 0 -68.97497)
			(size 2.8194 1.5748)
			(drill oval 2.4384 1.1938)
			(layers "*.Cu" "*.Mask")
			(remove_unused_layers no)
			(net "GND")
			(clearance 0.127)
			(thermal_gap 0.127)
		)
		(pad "G2" thru_hole oval
			(at 0 3.875024)
			(size 2.8194 1.5748)
			(drill oval 2.4384 1.1938)
			(layers "*.Cu" "*.Mask")
			(remove_unused_layers no)
			(net "GND")
			(clearance 0.127)
			(thermal_gap 0.127)
		)
		(pad "G3" thru_hole oval
			(at 0 68.97497)
			(size 2.8194 1.5748)
			(drill oval 2.4384 1.1938)
			(layers "*.Cu" "*.Mask")
			(remove_unused_layers no)
			(net "GND")
			(clearance 0.127)
			(thermal_gap 0.127)
		)
	)
)
